(kicad_pcb
	(version 20260206)
	(generator "pcbnew")
	(generator_version "10.0")
	(general
		(thickness 1.6)
		(legacy_teardrops no)
	)
	(paper "A4")
	(title_block
		(title "Wiwynn_Tioga_Pass_MB.brd")
		(comment 1 "Tioga Pass / footprints 4397-4402 of 4770")
	)
	(layers
		(0 "F.Cu" signal "TOP")
		(4 "In1.Cu" signal "L2GND")
		(6 "In2.Cu" signal "L3")
		(8 "In3.Cu" signal "L4GND")
		(10 "In4.Cu" signal "L5")
		(12 "In5.Cu" signal "L6GND")
		(14 "In6.Cu" signal "L7VCC")
		(16 "In7.Cu" signal "L8VCC")
		(18 "In8.Cu" signal "L9GND")
		(20 "In9.Cu" signal "L10")
		(22 "In10.Cu" signal "L11GND")
		(24 "In11.Cu" signal "L12")
		(26 "In12.Cu" signal "L13GND")
		(2 "B.Cu" signal "BOTTOM")
		(9 "F.Adhes" user "F.Adhesive")
		(11 "B.Adhes" user "B.Adhesive")
		(13 "F.Paste" user "Package Geometry/Pastemask Top")
		(15 "B.Paste" user "Package Geometry/Pastemask Bottom")
		(5 "F.SilkS" user "Ref Des/Silkscreen Top")
		(7 "B.SilkS" user "Ref Des/Silkscreen Bottom")
		(1 "F.Mask" user "Board Geometry/Soldermask Top")
		(3 "B.Mask" user "Board Geometry/Soldermask Bottom")
		(17 "Dwgs.User" user "User.Drawings")
		(19 "Cmts.User" user "User.Comments")
		(21 "Eco1.User" user "User.Eco1")
		(23 "Eco2.User" user "User.Eco2")
		(25 "Edge.Cuts" user "Board Geometry/Outline")
		(27 "Margin" user)
		(31 "F.CrtYd" user "Package Geometry/Place Bound Top")
		(29 "B.CrtYd" user "Package Geometry/Place Bound Bottom")
		(35 "F.Fab" user "Ref Des/Assembly Top")
		(33 "B.Fab" user "Ref Des/Assembly Bottom")
	)
	(footprint ""
		(layer "B.Cu")
		(at 438.604406 -32.100774 90)
		(property "Reference" "R1T40"
			(at 0.8382 -0.67818 90)
			(unlocked yes)
			(layer "B.SilkS")
			(effects
				(font
					(size 0.4064 0.254)
					(thickness 0.1524)
				)
				(justify left mirror)
			)
		)
		(property "Value" ""
			(at 0 0 90)
			(layer "B.Fab")
			(effects
				(font
					(size 1.27 1.27)
				)
				(justify mirror)
			)
		)
		(duplicate_pad_numbers_are_jumpers no)
		(fp_poly
			(pts
				(xy 0.2794 -0.1016) (xy -0.2794 -0.1016) (xy -0.2794 0.9906) (xy 0.2794 0.9906)
			)
			(stroke
				(width 0)
				(type default)
			)
			(fill no)
			(layer "B.CrtYd")
		)
		(fp_line
			(start 0.2794 -0.1016)
			(end 0.2794 0.9906)
			(stroke
				(width 0.1)
				(type default)
			)
			(layer "B.Fab")
		)
		(fp_line
			(start -0.2794 -0.1016)
			(end 0.2794 -0.1016)
			(stroke
				(width 0.1)
				(type default)
			)
			(layer "B.Fab")
		)
		(fp_line
			(start 0.2794 0.9906)
			(end -0.2794 0.9906)
			(stroke
				(width 0.1)
				(type default)
			)
			(layer "B.Fab")
		)
		(fp_line
			(start -0.2794 0.9906)
			(end -0.2794 -0.1016)
			(stroke
				(width 0.1)
				(type default)
			)
			(layer "B.Fab")
		)
		(pad "1" smd rect
			(at 0 0 270)
			(size 0.508 0.508)
			(layers "B.Cu" "B.Mask" "B.Paste")
			(net "BMC_M_CLK_DP")
		)
		(pad "2" smd rect
			(at 0 0.889 270)
			(size 0.508 0.508)
			(layers "B.Cu" "B.Mask" "B.Paste")
			(net "BMC_M_CLK")
		)
		(zone
			(layer "B.Cu")
			(hatch none 0.5)
			(connect_pads
				(clearance 0)
			)
			(min_thickness 0.25)
			(keepout
				(tracks allowed)
				(vias not_allowed)
				(pads allowed)
				(copperpour not_allowed)
				(footprints allowed)
			)
			(placement
				(enabled no)
				(sheetname "")
			)
			(fill
				(thermal_gap 0.5)
				(thermal_bridge_width 0.5)
				(island_removal_mode 0)
			)
			(polygon
				(pts
					(xy 438.858406 -32.354774) (xy 438.858406 -31.846774) (xy 439.239406 -31.846774) (xy 439.239406 -32.354774)
				)
			)
		)
		(zone
			(layer "B.Cu")
			(hatch none 0.5)
			(connect_pads
				(clearance 0)
			)
			(min_thickness 0.25)
			(keepout
				(tracks not_allowed)
				(vias allowed)
				(pads allowed)
				(copperpour not_allowed)
				(footprints allowed)
			)
			(placement
				(enabled no)
				(sheetname "")
			)
			(fill
				(thermal_gap 0.5)
				(thermal_bridge_width 0.5)
				(island_removal_mode 0)
			)
			(polygon
				(pts
					(xy 439.239406 -32.354774) (xy 439.239406 -31.846774) (xy 438.858406 -31.846774) (xy 438.858406 -32.354774)
				)
			)
		)
	)
	(footprint ""
		(layer "B.Cu")
		(at 45.212 -67.945 -90)
		(property "Reference" "C9P23"
			(at 0.53467 -3.937 0)
			(unlocked yes)
			(layer "B.SilkS")
			(effects
				(font
					(size 0.7874 0.5842)
					(thickness 0.1524)
				)
				(justify mirror)
			)
		)
		(property "Value" ""
			(at 0 0 90)
			(layer "B.Fab")
			(effects
				(font
					(size 1.27 1.27)
				)
				(justify mirror)
			)
		)
		(duplicate_pad_numbers_are_jumpers no)
		(fp_line
			(start -2.286 7.366)
			(end -1.600708 7.366)
			(stroke
				(width 0.1524)
				(type default)
			)
			(layer "B.SilkS")
		)
		(fp_line
			(start -2.286 7.366)
			(end -2.286 1.63195)
			(stroke
				(width 0.1524)
				(type default)
			)
			(layer "B.SilkS")
		)
		(fp_line
			(start 2.286 7.366)
			(end 1.60147 7.366)
			(stroke
				(width 0.1524)
				(type default)
			)
			(layer "B.SilkS")
		)
		(fp_line
			(start 2.286 7.366)
			(end 2.286 1.632712)
			(stroke
				(width 0.1524)
				(type default)
			)
			(layer "B.SilkS")
		)
		(fp_line
			(start -2.504948 1.633728)
			(end -1.6002 1.633728)
			(stroke
				(width 0.1524)
				(type default)
			)
			(layer "B.SilkS")
		)
		(fp_line
			(start 2.563114 1.633728)
			(end 1.6002 1.633728)
			(stroke
				(width 0.1524)
				(type default)
			)
			(layer "B.SilkS")
		)
		(fp_line
			(start -2.504948 -1.616456)
			(end -2.504948 1.633728)
			(stroke
				(width 0.1524)
				(type default)
			)
			(layer "B.SilkS")
		)
		(fp_line
			(start -1.6002 -1.616456)
			(end -2.504948 -1.616456)
			(stroke
				(width 0.1524)
				(type default)
			)
			(layer "B.SilkS")
		)
		(fp_line
			(start 1.6002 -1.616456)
			(end 2.563114 -1.616456)
			(stroke
				(width 0.1524)
				(type default)
			)
			(layer "B.SilkS")
		)
		(fp_line
			(start 2.563114 -1.616456)
			(end 2.563114 1.633728)
			(stroke
				(width 0.1524)
				(type default)
			)
			(layer "B.SilkS")
		)
		(fp_rect
			(start 2.286 7.366)
			(end -2.286 -0.254)
			(stroke
				(width 0)
				(type default)
			)
			(fill no)
			(layer "B.CrtYd")
		)
		(fp_line
			(start -2.286 7.366)
			(end 2.286 7.366)
			(stroke
				(width 0.1)
				(type default)
			)
			(layer "B.Fab")
		)
		(fp_line
			(start 2.286 7.366)
			(end 2.286 -0.254)
			(stroke
				(width 0.1)
				(type default)
			)
			(layer "B.Fab")
		)
		(fp_line
			(start -2.286 -0.254)
			(end -2.286 7.366)
			(stroke
				(width 0.1)
				(type default)
			)
			(layer "B.Fab")
		)
		(fp_line
			(start 2.286 -0.254)
			(end -2.286 -0.254)
			(stroke
				(width 0.1)
				(type default)
			)
			(layer "B.Fab")
		)
		(pad "1" smd rect
			(at 0 0 90)
			(size 2.54 3.048)
			(layers "B.Cu" "B.Mask" "B.Paste")
			(net "PVCCIN_CPU1")
		)
		(pad "2" smd rect
			(at 0 7.112 90)
			(size 2.54 3.048)
			(layers "B.Cu" "B.Mask" "B.Paste")
			(net "GND")
		)
	)
	(footprint ""
		(layer "B.Cu")
		(at 390.635744 -22.543516 -90)
		(property "Reference" "C2T26"
			(at 0 0 90)
			(layer "B.SilkS")
			(hide yes)
			(effects
				(font
					(size 1.27 1.27)
				)
				(justify mirror)
			)
		)
		(property "Value" ""
			(at 0 0 90)
			(layer "B.Fab")
			(effects
				(font
					(size 1.27 1.27)
				)
				(justify mirror)
			)
		)
		(duplicate_pad_numbers_are_jumpers no)
		(fp_poly
			(pts
				(xy -0.3048 -0.1016) (xy -0.3048 0.9906) (xy 0.3048 0.9906) (xy 0.3048 -0.1016)
			)
			(stroke
				(width 0)
				(type default)
			)
			(fill no)
			(layer "B.CrtYd")
		)
		(fp_line
			(start -0.3048 0.9906)
			(end -0.3048 -0.1016)
			(stroke
				(width 0.1)
				(type default)
			)
			(layer "B.Fab")
		)
		(fp_line
			(start 0.3048 0.9906)
			(end -0.3048 0.9906)
			(stroke
				(width 0.1)
				(type default)
			)
			(layer "B.Fab")
		)
		(fp_line
			(start -0.3048 -0.1016)
			(end 0.3048 -0.1016)
			(stroke
				(width 0.1)
				(type default)
			)
			(layer "B.Fab")
		)
		(fp_line
			(start 0.3048 -0.1016)
			(end 0.3048 0.9906)
			(stroke
				(width 0.1)
				(type default)
			)
			(layer "B.Fab")
		)
		(pad "1" smd rect
			(at 0 0 90)
			(size 0.508 0.508)
			(layers "B.Cu" "B.Mask" "B.Paste")
			(net "P3V3")
		)
		(pad "2" smd rect
			(at 0 0.889 90)
			(size 0.508 0.508)
			(layers "B.Cu" "B.Mask" "B.Paste")
			(net "GND")
		)
		(zone
			(layer "B.Cu")
			(hatch none 0.5)
			(connect_pads
				(clearance 0)
			)
			(min_thickness 0.25)
			(keepout
				(tracks not_allowed)
				(vias allowed)
				(pads allowed)
				(copperpour not_allowed)
				(footprints allowed)
			)
			(placement
				(enabled no)
				(sheetname "")
			)
			(fill
				(thermal_gap 0.5)
				(thermal_bridge_width 0.5)
				(island_removal_mode 0)
			)
			(polygon
				(pts
					(xy 390.000744 -22.289516) (xy 390.000744 -22.797516) (xy 390.381744 -22.797516) (xy 390.381744 -22.289516)
				)
			)
		)
		(zone
			(layer "B.Cu")
			(hatch none 0.5)
			(connect_pads
				(clearance 0)
			)
			(min_thickness 0.25)
			(keepout
				(tracks allowed)
				(vias not_allowed)
				(pads allowed)
				(copperpour not_allowed)
				(footprints allowed)
			)
			(placement
				(enabled no)
				(sheetname "")
			)
			(fill
				(thermal_gap 0.5)
				(thermal_bridge_width 0.5)
				(island_removal_mode 0)
			)
			(polygon
				(pts
					(xy 390.381744 -22.289516) (xy 390.381744 -22.797516) (xy 390.000744 -22.797516) (xy 390.000744 -22.289516)
				)
			)
		)
	)
	(footprint ""
		(layer "B.Cu")
		(at 352.8949 -72.8218 -90)
		(property "Reference" "R7D40"
			(at 0 0 90)
			(layer "B.SilkS")
			(hide yes)
			(effects
				(font
					(size 1.27 1.27)
				)
				(justify mirror)
			)
		)
		(property "Value" ""
			(at 0 0 90)
			(layer "B.Fab")
			(effects
				(font
					(size 1.27 1.27)
				)
				(justify mirror)
			)
		)
		(duplicate_pad_numbers_are_jumpers no)
		(fp_poly
			(pts
				(xy 0.2794 -0.1016) (xy -0.2794 -0.1016) (xy -0.2794 0.9906) (xy 0.2794 0.9906)
			)
			(stroke
				(width 0)
				(type default)
			)
			(fill no)
			(layer "B.CrtYd")
		)
		(fp_line
			(start -0.2794 0.9906)
			(end -0.2794 -0.1016)
			(stroke
				(width 0.1)
				(type default)
			)
			(layer "B.Fab")
		)
		(fp_line
			(start 0.2794 0.9906)
			(end -0.2794 0.9906)
			(stroke
				(width 0.1)
				(type default)
			)
			(layer "B.Fab")
		)
		(fp_line
			(start -0.2794 -0.1016)
			(end 0.2794 -0.1016)
			(stroke
				(width 0.1)
				(type default)
			)
			(layer "B.Fab")
		)
		(fp_line
			(start 0.2794 -0.1016)
			(end 0.2794 0.9906)
			(stroke
				(width 0.1)
				(type default)
			)
			(layer "B.Fab")
		)
		(pad "1" smd rect
			(at 0 0 90)
			(size 0.508 0.508)
			(layers "B.Cu" "B.Mask" "B.Paste")
			(net "FM_CPU0_VRM_OSC_EN")
		)
		(pad "2" smd rect
			(at 0 0.889 90)
			(size 0.508 0.508)
			(layers "B.Cu" "B.Mask" "B.Paste")
			(net "FM_CPU0_STL_BRD_OSC_EN")
		)
		(zone
			(layer "B.Cu")
			(hatch none 0.5)
			(connect_pads
				(clearance 0)
			)
			(min_thickness 0.25)
			(keepout
				(tracks not_allowed)
				(vias allowed)
				(pads allowed)
				(copperpour not_allowed)
				(footprints allowed)
			)
			(placement
				(enabled no)
				(sheetname "")
			)
			(fill
				(thermal_gap 0.5)
				(thermal_bridge_width 0.5)
				(island_removal_mode 0)
			)
			(polygon
				(pts
					(xy 352.2599 -72.5678) (xy 352.2599 -73.0758) (xy 352.6409 -73.0758) (xy 352.6409 -72.5678)
				)
			)
		)
		(zone
			(layer "B.Cu")
			(hatch none 0.5)
			(connect_pads
				(clearance 0)
			)
			(min_thickness 0.25)
			(keepout
				(tracks allowed)
				(vias not_allowed)
				(pads allowed)
				(copperpour not_allowed)
				(footprints allowed)
			)
			(placement
				(enabled no)
				(sheetname "")
			)
			(fill
				(thermal_gap 0.5)
				(thermal_bridge_width 0.5)
				(island_removal_mode 0)
			)
			(polygon
				(pts
					(xy 352.6409 -72.5678) (xy 352.6409 -73.0758) (xy 352.2599 -73.0758) (xy 352.2599 -72.5678)
				)
			)
		)
	)
	(footprint ""
		(layer "B.Cu")
		(at 497.743226 -34.715704 90)
		(property "Reference" "R9F66"
			(at 0 0 90)
			(layer "B.SilkS")
			(hide yes)
			(effects
				(font
					(size 1.27 1.27)
				)
				(justify mirror)
			)
		)
		(property "Value" ""
			(at 0 0 90)
			(layer "B.Fab")
			(effects
				(font
					(size 1.27 1.27)
				)
				(justify mirror)
			)
		)
		(duplicate_pad_numbers_are_jumpers no)
		(fp_poly
			(pts
				(xy 0.2794 -0.1016) (xy -0.2794 -0.1016) (xy -0.2794 0.9906) (xy 0.2794 0.9906)
			)
			(stroke
				(width 0)
				(type default)
			)
			(fill no)
			(layer "B.CrtYd")
		)
		(fp_line
			(start 0.2794 -0.1016)
			(end 0.2794 0.9906)
			(stroke
				(width 0.1)
				(type default)
			)
			(layer "B.Fab")
		)
		(fp_line
			(start -0.2794 -0.1016)
			(end 0.2794 -0.1016)
			(stroke
				(width 0.1)
				(type default)
			)
			(layer "B.Fab")
		)
		(fp_line
			(start 0.2794 0.9906)
			(end -0.2794 0.9906)
			(stroke
				(width 0.1)
				(type default)
			)
			(layer "B.Fab")
		)
		(fp_line
			(start -0.2794 0.9906)
			(end -0.2794 -0.1016)
			(stroke
				(width 0.1)
				(type default)
			)
			(layer "B.Fab")
		)
		(pad "1" smd rect
			(at 0 0 270)
			(size 0.508 0.508)
			(layers "B.Cu" "B.Mask" "B.Paste")
			(net "SP2_BMC_CM_UART_TX")
		)
		(pad "2" smd rect
			(at 0 0.889 270)
			(size 0.508 0.508)
			(layers "B.Cu" "B.Mask" "B.Paste")
			(net "SP2_BMC_CM_UART_TX_R")
		)
		(zone
			(layer "B.Cu")
			(hatch none 0.5)
			(connect_pads
				(clearance 0)
			)
			(min_thickness 0.25)
			(keepout
				(tracks allowed)
				(vias not_allowed)
				(pads allowed)
				(copperpour not_allowed)
				(footprints allowed)
			)
			(placement
				(enabled no)
				(sheetname "")
			)
			(fill
				(thermal_gap 0.5)
				(thermal_bridge_width 0.5)
				(island_removal_mode 0)
			)
			(polygon
				(pts
					(xy 497.997226 -34.969704) (xy 497.997226 -34.461704) (xy 498.378226 -34.461704) (xy 498.378226 -34.969704)
				)
			)
		)
		(zone
			(layer "B.Cu")
			(hatch none 0.5)
			(connect_pads
				(clearance 0)
			)
			(min_thickness 0.25)
			(keepout
				(tracks not_allowed)
				(vias allowed)
				(pads allowed)
				(copperpour not_allowed)
				(footprints allowed)
			)
			(placement
				(enabled no)
				(sheetname "")
			)
			(fill
				(thermal_gap 0.5)
				(thermal_bridge_width 0.5)
				(island_removal_mode 0)
			)
			(polygon
				(pts
					(xy 498.378226 -34.969704) (xy 498.378226 -34.461704) (xy 497.997226 -34.461704) (xy 497.997226 -34.969704)
				)
			)
		)
	)
	(footprint ""
		(layer "B.Cu")
		(at 316.3443 -164.9095 -90)
		(property "Reference" "T1D17"
			(at 0 0 90)
			(layer "B.SilkS")
			(hide yes)
			(effects
				(font
					(size 1.27 1.27)
				)
				(justify mirror)
			)
		)
		(property "Value" "*"
			(at 3.4036 -4.46405 270)
			(unlocked yes)
			(layer "B.Fab")
			(hide yes)
			(effects
				(font
					(size 0.889 0.889)
					(thickness 0.1524)
				)
				(justify mirror)
			)
		)
		(property "Device Type" "TEST-PAD-12P-1-GP-U_DISCRET-GBA"
			(at 3.4036 -5.98805 270)
			(unlocked yes)
			(layer "B.Fab")
			(hide yes)
			(effects
				(font
					(size 0.889 0.889)
					(thickness 0.1524)
				)
				(justify mirror)
			)
		)
		(duplicate_pad_numbers_are_jumpers no)
		(fp_line
			(start -2.3622 3.4798)
			(end 2.3876 3.4798)
			(stroke
				(width 0.1524)
				(type default)
			)
			(layer "B.SilkS")
		)
		(fp_line
			(start 2.3876 3.4798)
			(end 2.3876 -4.826)
			(stroke
				(width 0.1524)
				(type default)
			)
			(layer "B.SilkS")
		)
		(fp_line
			(start -2.3622 -4.826)
			(end -2.3622 3.4798)
			(stroke
				(width 0.1524)
				(type default)
			)
			(layer "B.SilkS")
		)
		(fp_line
			(start 2.3876 -4.826)
			(end -2.3622 -4.826)
			(stroke
				(width 0.1524)
				(type default)
			)
			(layer "B.SilkS")
		)
		(fp_rect
			(start 2.6416 3.7338)
			(end -2.6162 -5.08)
			(stroke
				(width 0)
				(type default)
			)
			(fill no)
			(layer "B.CrtYd")
		)
		(fp_rect
			(start 2.6416 3.7338)
			(end -2.6162 -5.08)
			(stroke
				(width 0)
				(type default)
			)
			(fill no)
			(layer "B.Fab")
		)
		(pad "1" smd circle
			(at -0.496824 -1.301496 90)
			(size 0.6604 0.6604)
			(layers "B.Cu" "B.Mask" "B.Paste")
			(net "L5_85OHM_10INCH_DP")
		)
		(pad "2" smd circle
			(at 0.503936 -1.301496 90)
			(size 0.6604 0.6604)
			(layers "B.Cu" "B.Mask" "B.Paste")
			(net "L5_85OHM_10INCH_DN")
		)
		(pad "3" smd custom
			(at 0.00889 0.370078 90)
			(size 0.74295 0.74295)
			(layers "B.Cu" "B.Mask" "B.Paste")
			(net "GND")
			(options
				(clearance outline)
				(anchor circle)
			)
			(primitives
				(gr_poly
					(pts
						(xy -2.1209 -1.4859) (xy 2.1209 -1.4859) (xy 2.1209 1.4859) (xy 1.08585 1.4859) (xy 1.08585 0.4699)
						(xy -1.08585 0.4699) (xy -1.08585 1.4859) (xy -2.1209 1.4859)
					)
					(width 0)
					(fill yes)
				)
			)
		)
		(pad "4" thru_hole circle
			(at -1.266444 -3.851656 90)
			(size 1.4478 1.4478)
			(drill 1.0414)
			(layers "*.Cu" "*.Mask")
			(remove_unused_layers no)
			(net "GND")
			(clearance 0.1524)
			(thermal_gap 0.1524)
		)
		(pad "5" thru_hole circle
			(at 1.273556 -3.851656 90)
			(size 1.4478 1.4478)
			(drill 1.0414)
			(layers "*.Cu" "*.Mask")
			(remove_unused_layers no)
			(net "GND")
			(clearance 0.1524)
			(thermal_gap 0.1524)
		)
		(pad "6" thru_hole circle
			(at -1.266444 2.498344 90)
			(size 1.4478 1.4478)
			(drill 1.0414)
			(layers "*.Cu" "*.Mask")
			(remove_unused_layers no)
			(net "GND")
			(clearance 0.1524)
			(thermal_gap 0.1524)
		)
		(pad "7" thru_hole circle
			(at 1.273556 2.498344 90)
			(size 1.4478 1.4478)
			(drill 1.0414)
			(layers "*.Cu" "*.Mask")
			(remove_unused_layers no)
			(net "GND")
			(clearance 0.1524)
			(thermal_gap 0.1524)
		)
		(pad "8" thru_hole circle
			(at -1.27 -0.4572 90)
			(size 0.7112 0.7112)
			(drill 0.4064)
			(layers "*.Cu" "*.Mask")
			(remove_unused_layers no)
			(net "GND")
			(clearance 0.1016)
			(thermal_gap 0.1016)
		)
		(pad "9" thru_hole circle
			(at -1.27 0.762 90)
			(size 0.7112 0.7112)
			(drill 0.4064)
			(layers "*.Cu" "*.Mask")
			(remove_unused_layers no)
			(net "GND")
			(clearance 0.1016)
			(thermal_gap 0.1016)
		)
		(pad "10" thru_hole circle
			(at 0.0254 0.762 90)
			(size 0.7112 0.7112)
			(drill 0.4064)
			(layers "*.Cu" "*.Mask")
			(remove_unused_layers no)
			(net "GND")
			(clearance 0.1016)
			(thermal_gap 0.1016)
		)
		(pad "11" thru_hole circle
			(at 1.27 0.762 90)
			(size 0.7112 0.7112)
			(drill 0.4064)
			(layers "*.Cu" "*.Mask")
			(remove_unused_layers no)
			(net "GND")
			(clearance 0.1016)
			(thermal_gap 0.1016)
		)
		(pad "12" thru_hole circle
			(at 1.27 -0.4572 90)
			(size 0.7112 0.7112)
			(drill 0.4064)
			(layers "*.Cu" "*.Mask")
			(remove_unused_layers no)
			(net "GND")
			(clearance 0.1016)
			(thermal_gap 0.1016)
		)
	)
)
